(kicad_pcb
	(version 20260206)
	(generator "pcbnew")
	(generator_version "10.0")
	(general
		(thickness 1.6)
		(legacy_teardrops no)
	)
	(paper "A4")
	(title_block
		(title "v1-chassis-manager — T6M_CM_d_v01_1031_1645.brd")
		(comment 1 "Open CloudServer (Microsoft) / footprints 289-295 of 2512")
	)
	(layers
		(0 "F.Cu" signal "TOP")
		(4 "In1.Cu" signal "GND1")
		(6 "In2.Cu" signal "IN1")
		(8 "In3.Cu" signal "VCC1")
		(10 "In4.Cu" signal "VCC2")
		(12 "In5.Cu" signal "GND2")
		(14 "In6.Cu" signal "IN2")
		(16 "In7.Cu" signal "IN3")
		(18 "In8.Cu" signal "GND3")
		(2 "B.Cu" signal "BOTTOM")
		(9 "F.Adhes" user "F.Adhesive")
		(11 "B.Adhes" user "B.Adhesive")
		(13 "F.Paste" user "Package Geometry/Pastemask Top")
		(15 "B.Paste" user "Package Geometry/Pastemask Bottom")
		(5 "F.SilkS" user "Ref Des/Silkscreen Top")
		(7 "B.SilkS" user "Ref Des/Silkscreen Bottom")
		(1 "F.Mask" user "Board Geometry/Soldermask Top")
		(3 "B.Mask" user "Board Geometry/Soldermask Bottom")
		(17 "Dwgs.User" user "User.Drawings")
		(19 "Cmts.User" user "User.Comments")
		(21 "Eco1.User" user "User.Eco1")
		(23 "Eco2.User" user "User.Eco2")
		(25 "Edge.Cuts" user "Board Geometry/Outline")
		(27 "Margin" user)
		(31 "F.CrtYd" user "Package Geometry/Place Bound Top")
		(29 "B.CrtYd" user "Package Geometry/Place Bound Bottom")
		(35 "F.Fab" user "Ref Des/Assembly Top")
		(33 "B.Fab" user "Ref Des/Assembly Bottom")
	)
	(footprint ""
		(layer "F.Cu")
		(at 153.872184 -44.41063 180)
		(property "Reference" "J7"
			(at -4.145026 2.643124 90)
			(unlocked yes)
			(layer "F.SilkS")
			(effects
				(font
					(size 0.7874 0.5842)
					(thickness 0.1524)
				)
				(justify left)
			)
		)
		(property "Value" ""
			(at 0 0 180)
			(layer "F.Fab")
			(effects
				(font
					(size 1.27 1.27)
				)
			)
		)
		(duplicate_pad_numbers_are_jumpers no)
		(fp_line
			(start 2.949956 11.73988)
			(end 2.949956 -4.260088)
			(stroke
				(width 0.1524)
				(type default)
			)
			(layer "F.SilkS")
		)
		(fp_line
			(start 0.145796 8.845296)
			(end 0.145796 8.464296)
			(stroke
				(width 0.1524)
				(type default)
			)
			(layer "F.SilkS")
		)
		(fp_line
			(start 0.145796 8.464296)
			(end -2.597404 8.464296)
			(stroke
				(width 0.1524)
				(type default)
			)
			(layer "F.SilkS")
		)
		(fp_line
			(start -2.597404 8.464296)
			(end -2.597404 -0.298704)
			(stroke
				(width 0.1524)
				(type default)
			)
			(layer "F.SilkS")
		)
		(fp_line
			(start -2.597404 -0.298704)
			(end -2.902204 -0.298704)
			(stroke
				(width 0.1524)
				(type default)
			)
			(layer "F.SilkS")
		)
		(fp_line
			(start -2.902204 8.845296)
			(end 0.145796 8.845296)
			(stroke
				(width 0.1524)
				(type default)
			)
			(layer "F.SilkS")
		)
		(fp_line
			(start -2.902204 -0.298704)
			(end -2.902204 8.845296)
			(stroke
				(width 0.1524)
				(type default)
			)
			(layer "F.SilkS")
		)
		(fp_line
			(start -3.50012 11.73988)
			(end 2.949956 11.73988)
			(stroke
				(width 0.1524)
				(type default)
			)
			(layer "F.SilkS")
		)
		(fp_line
			(start -3.50012 11.73988)
			(end -3.50012 -4.260088)
			(stroke
				(width 0.1524)
				(type default)
			)
			(layer "F.SilkS")
		)
		(fp_line
			(start -3.50012 -4.260088)
			(end 2.949956 -4.260088)
			(stroke
				(width 0.1524)
				(type default)
			)
			(layer "F.SilkS")
		)
		(fp_poly
			(pts
				(xy -2.050542 8.210296) (xy 0.591058 8.210296) (xy 0.591058 -0.603504) (xy -2.050542 -0.603504)
				(xy -2.101342 -0.603504) (xy -2.101342 8.210296)
			)
			(stroke
				(width 0)
				(type default)
			)
			(fill no)
			(layer "B.CrtYd")
		)
		(fp_poly
			(pts
				(arc
					(start -1.015492 -2.45999)
					(mid 1.015492 -2.45999)
					(end -1.015492 -2.45999)
				)
			)
			(stroke
				(width 0)
				(type default)
			)
			(fill no)
			(layer "B.CrtYd")
		)
		(fp_poly
			(pts
				(arc
					(start -2.016506 10.370058)
					(mid 0.01651 10.370058)
					(end -2.016506 10.370058)
				)
			)
			(stroke
				(width 0)
				(type default)
			)
			(fill no)
			(layer "B.CrtYd")
		)
		(fp_poly
			(pts
				(xy -0.020066 11.73988) (xy 2.949956 11.73988) (xy 2.949956 -4.260088) (xy -3.50012 -4.260088) (xy -3.50012 11.73988)
			)
			(stroke
				(width 0)
				(type default)
			)
			(fill no)
			(layer "F.CrtYd")
		)
		(fp_line
			(start 2.949956 11.73988)
			(end 2.949956 -4.260088)
			(stroke
				(width 0.1)
				(type default)
			)
			(layer "F.Fab")
		)
		(fp_line
			(start 2.949956 -4.260088)
			(end -3.50012 -4.260088)
			(stroke
				(width 0.1)
				(type default)
			)
			(layer "F.Fab")
		)
		(fp_line
			(start -0.020066 11.73988)
			(end 2.949956 11.73988)
			(stroke
				(width 0.1)
				(type default)
			)
			(layer "F.Fab")
		)
		(fp_line
			(start -3.50012 11.73988)
			(end -0.020066 11.73988)
			(stroke
				(width 0.1)
				(type default)
			)
			(layer "F.Fab")
		)
		(fp_line
			(start -3.50012 -4.260088)
			(end -3.50012 11.73988)
			(stroke
				(width 0.1)
				(type default)
			)
			(layer "F.Fab")
		)
		(fp_text user "1"
			(at -2.154936 -5.000244 0)
			(unlocked yes)
			(layer "F.SilkS")
			(effects
				(font
					(size 0.635 0.4064)
					(thickness 0.1524)
				)
				(justify left)
			)
		)
		(fp_text user "7"
			(at -3.864356 8.262874 0)
			(unlocked yes)
			(layer "F.SilkS")
			(effects
				(font
					(size 0.635 0.4064)
					(thickness 0.1524)
				)
				(justify left)
			)
		)
		(fp_text user "1"
			(at 1.365758 0.058674 0)
			(unlocked yes)
			(layer "B.SilkS")
			(effects
				(font
					(size 0.7874 0.5842)
					(thickness 0.1524)
				)
				(justify left mirror)
			)
		)
		(fp_text user "7"
			(at 0.956564 7.765034 0)
			(unlocked yes)
			(layer "B.SilkS")
			(effects
				(font
					(size 0.7874 0.5842)
					(thickness 0.1524)
				)
				(justify left mirror)
			)
		)
		(fp_text user "7"
			(at 1.15824 7.257796 270)
			(unlocked yes)
			(layer "B.Fab")
			(effects
				(font
					(size 0.7874 0.5842)
					(thickness 0.000001)
				)
				(justify left mirror)
			)
		)
		(fp_text user "1"
			(at 1.10744 -0.260604 270)
			(unlocked yes)
			(layer "B.Fab")
			(effects
				(font
					(size 0.7874 0.5842)
					(thickness 0.000001)
				)
				(justify left mirror)
			)
		)
		(fp_text user "7"
			(at -3.97256 7.841996 270)
			(unlocked yes)
			(layer "F.Fab")
			(effects
				(font
					(size 0.7874 0.5842)
					(thickness 0.000001)
				)
				(justify left)
			)
		)
		(fp_text user "1"
			(at -4.111498 0.755396 270)
			(unlocked yes)
			(layer "F.Fab")
			(effects
				(font
					(size 0.7874 0.5842)
					(thickness 0.000001)
				)
				(justify left)
			)
		)
		(pad "1" thru_hole rect
			(at 0 0 270)
			(size 1.0668 1.0668)
			(drill 0.6604)
			(layers "*.Cu" "*.Mask")
			(remove_unused_layers no)
			(net "GND")
			(clearance 0.0508)
			(thermal_gap 0.0508)
			(padstack
				(mode front_inner_back)
				(layer "Inner"
					(shape circle)
					(size 1.0668 1.0668)
					(clearance 0.0508)
				)
				(layer "B.Cu"
					(shape rect)
					(size 1.0668 1.0668)
					(clearance 0.0508)
				)
			)
		)
		(pad "2" thru_hole circle
			(at -1.500124 1.054608 270)
			(size 1.0668 1.0668)
			(drill 0.6604)
			(layers "*.Cu" "*.Mask")
			(remove_unused_layers no)
			(net "SATA_TX0_C_DP")
			(clearance 0.0508)
			(thermal_gap 0.0508)
		)
		(pad "3" thru_hole circle
			(at -1.500124 2.75463 270)
			(size 1.0668 1.0668)
			(drill 0.6604)
			(layers "*.Cu" "*.Mask")
			(remove_unused_layers no)
			(net "SATA_TX0_C_DN")
			(clearance 0.0508)
			(thermal_gap 0.0508)
		)
		(pad "4" thru_hole circle
			(at 0 3.81 270)
			(size 1.0668 1.0668)
			(drill 0.6604)
			(layers "*.Cu" "*.Mask")
			(remove_unused_layers no)
			(net "GND")
			(clearance 0.0508)
			(thermal_gap 0.0508)
		)
		(pad "5" thru_hole circle
			(at -1.500124 4.864608 270)
			(size 1.0668 1.0668)
			(drill 0.6604)
			(layers "*.Cu" "*.Mask")
			(remove_unused_layers no)
			(net "SATA_RX0_C_DN")
			(clearance 0.0508)
			(thermal_gap 0.0508)
		)
		(pad "6" thru_hole circle
			(at -1.500124 6.56463 270)
			(size 1.0668 1.0668)
			(drill 0.6604)
			(layers "*.Cu" "*.Mask")
			(remove_unused_layers no)
			(net "SATA_RX0_C_DP")
			(clearance 0.0508)
			(thermal_gap 0.0508)
		)
		(pad "7" thru_hole circle
			(at 0 7.62 270)
			(size 1.0668 1.0668)
			(drill 0.6604)
			(layers "*.Cu" "*.Mask")
			(remove_unused_layers no)
			(net "SATA_P7")
			(clearance 0.0508)
			(thermal_gap 0.0508)
		)
		(pad "8" thru_hole circle
			(at 0 -2.45999 270)
			(size 1.9304 1.9304)
			(drill 1.4224)
			(layers "*.Cu" "*.Mask")
			(remove_unused_layers no)
			(net "GND")
			(clearance 0)
		)
		(pad "9" thru_hole circle
			(at -0.999998 10.370058 270)
			(size 1.9304 1.9304)
			(drill 1.4224)
			(layers "*.Cu" "*.Mask")
			(remove_unused_layers no)
			(net "GND")
			(clearance 0)
		)
	)
	(footprint ""
		(layer "F.Cu")
		(at 62.558422 -164.289232 90)
		(property "Reference" "R1110"
			(at 1.75514 0.208026 90)
			(unlocked yes)
			(layer "F.SilkS")
			(effects
				(font
					(size 0.7874 0.5842)
					(thickness 0.1524)
				)
				(justify left)
			)
		)
		(property "Value" ""
			(at 0 0 90)
			(layer "F.Fab")
			(effects
				(font
					(size 1.27 1.27)
				)
			)
		)
		(duplicate_pad_numbers_are_jumpers no)
		(fp_line
			(start 0.7874 -0.4064)
			(end 0.7874 0.4064)
			(stroke
				(width 0.1524)
				(type default)
			)
			(layer "F.SilkS")
		)
		(fp_line
			(start -0.7874 -0.4064)
			(end 0.7874 -0.4064)
			(stroke
				(width 0.1524)
				(type default)
			)
			(layer "F.SilkS")
		)
		(fp_line
			(start 0.7874 0.4064)
			(end -0.7874 0.4064)
			(stroke
				(width 0.1524)
				(type default)
			)
			(layer "F.SilkS")
		)
		(fp_line
			(start -0.7874 0.4064)
			(end -0.7874 -0.4064)
			(stroke
				(width 0.1524)
				(type default)
			)
			(layer "F.SilkS")
		)
		(fp_poly
			(pts
				(xy -0.508 0.2794) (xy -0.508 0.2286) (xy -0.635 0.2286) (xy -0.635 -0.254) (xy -0.5334 -0.254)
				(xy -0.5334 -0.2794) (xy 0.5334 -0.2794) (xy 0.5334 -0.254) (xy 0.635 -0.254) (xy 0.635 0.254) (xy 0.5334 0.254)
				(xy 0.5334 0.2794)
			)
			(stroke
				(width 0)
				(type default)
			)
			(fill no)
			(layer "F.CrtYd")
		)
		(pad "1" smd rect
			(at 0.40005 0 90)
			(size 0.4572 0.508)
			(layers "F.Cu" "F.Mask" "F.Paste")
			(net "GND")
		)
		(pad "2" smd rect
			(at -0.40005 0 90)
			(size 0.4572 0.508)
			(layers "F.Cu" "F.Mask" "F.Paste")
			(net "P5V_NODE1")
		)
	)
	(footprint ""
		(layer "F.Cu")
		(at 139.68476 -181.506622 -90)
		(property "Reference" "C901"
			(at 0.479044 -1.142746 90)
			(unlocked yes)
			(layer "F.SilkS")
			(effects
				(font
					(size 0.7874 0.5842)
					(thickness 0.1524)
				)
				(justify left)
			)
		)
		(property "Value" ""
			(at 0 0 270)
			(layer "F.Fab")
			(effects
				(font
					(size 1.27 1.27)
				)
			)
		)
		(duplicate_pad_numbers_are_jumpers no)
		(fp_line
			(start -0.7874 0.4064)
			(end -0.7874 -0.4064)
			(stroke
				(width 0.1524)
				(type default)
			)
			(layer "F.SilkS")
		)
		(fp_line
			(start 0.7874 0.4064)
			(end -0.7874 0.4064)
			(stroke
				(width 0.1524)
				(type default)
			)
			(layer "F.SilkS")
		)
		(fp_line
			(start 0 0.381)
			(end 0 -0.381)
			(stroke
				(width 0.1524)
				(type default)
			)
			(layer "F.SilkS")
		)
		(fp_line
			(start -0.7874 -0.4064)
			(end 0.7874 -0.4064)
			(stroke
				(width 0.1524)
				(type default)
			)
			(layer "F.SilkS")
		)
		(fp_line
			(start 0.7874 -0.4064)
			(end 0.7874 0.4064)
			(stroke
				(width 0.1524)
				(type default)
			)
			(layer "F.SilkS")
		)
		(fp_poly
			(pts
				(xy -0.5334 0.254) (xy -0.635 0.254) (xy -0.635 0.2286) (xy -0.635 -0.254) (xy -0.5334 -0.254) (xy -0.5334 -0.2794)
				(xy 0.5334 -0.2794) (xy 0.5334 -0.254) (xy 0.635 -0.254) (xy 0.635 0.254) (xy 0.5334 0.254) (xy 0.5334 0.2794)
				(xy -0.508 0.2794) (xy -0.5334 0.2794)
			)
			(stroke
				(width 0)
				(type default)
			)
			(fill no)
			(layer "F.CrtYd")
		)
		(pad "1" smd rect
			(at 0.40005 0 270)
			(size 0.4572 0.508)
			(layers "F.Cu" "F.Mask" "F.Paste")
			(net "P3V3_NODE1")
		)
		(pad "2" smd rect
			(at -0.40005 0 270)
			(size 0.4572 0.508)
			(layers "F.Cu" "F.Mask" "F.Paste")
			(net "GND")
		)
	)
	(footprint ""
		(layer "F.Cu")
		(at 165.011354 -184.067196 180)
		(property "Reference" "R1170"
			(at 4.889754 0.614934 0)
			(unlocked yes)
			(layer "F.SilkS")
			(effects
				(font
					(size 0.7874 0.5842)
					(thickness 0.1524)
				)
				(justify left)
			)
		)
		(property "Value" ""
			(at 0 0 180)
			(layer "F.Fab")
			(effects
				(font
					(size 1.27 1.27)
				)
			)
		)
		(duplicate_pad_numbers_are_jumpers no)
		(fp_line
			(start 0.7874 0.4064)
			(end -0.7874 0.4064)
			(stroke
				(width 0.1524)
				(type default)
			)
			(layer "F.SilkS")
		)
		(fp_line
			(start 0.7874 -0.4064)
			(end 0.7874 0.4064)
			(stroke
				(width 0.1524)
				(type default)
			)
			(layer "F.SilkS")
		)
		(fp_line
			(start -0.7874 0.4064)
			(end -0.7874 -0.4064)
			(stroke
				(width 0.1524)
				(type default)
			)
			(layer "F.SilkS")
		)
		(fp_line
			(start -0.7874 -0.4064)
			(end 0.7874 -0.4064)
			(stroke
				(width 0.1524)
				(type default)
			)
			(layer "F.SilkS")
		)
		(fp_poly
			(pts
				(xy -0.508 0.2794) (xy -0.508 0.2286) (xy -0.635 0.2286) (xy -0.635 -0.254) (xy -0.5334 -0.254)
				(xy -0.5334 -0.2794) (xy 0.5334 -0.2794) (xy 0.5334 -0.254) (xy 0.635 -0.254) (xy 0.635 0.254) (xy 0.5334 0.254)
				(xy 0.5334 0.2794)
			)
			(stroke
				(width 0)
				(type default)
			)
			(fill no)
			(layer "F.CrtYd")
		)
		(pad "1" smd rect
			(at 0.40005 0 180)
			(size 0.4572 0.508)
			(layers "F.Cu" "F.Mask" "F.Paste")
			(net "CPLD_UART_DTR_P3_R_N")
		)
		(pad "2" smd rect
			(at -0.40005 0 180)
			(size 0.4572 0.508)
			(layers "F.Cu" "F.Mask" "F.Paste")
			(net "CPLD_UART_DTR_P3_N")
		)
	)
	(footprint ""
		(layer "F.Cu")
		(at 122.818652 -26.574242 90)
		(property "Reference" "R624"
			(at -5.330444 0.35687 90)
			(unlocked yes)
			(layer "F.SilkS")
			(effects
				(font
					(size 0.7874 0.5842)
					(thickness 0.1524)
				)
				(justify left)
			)
		)
		(property "Value" ""
			(at 0 0 90)
			(layer "F.Fab")
			(effects
				(font
					(size 1.27 1.27)
				)
			)
		)
		(duplicate_pad_numbers_are_jumpers no)
		(fp_line
			(start 0.7874 -0.4064)
			(end 0.7874 0.4064)
			(stroke
				(width 0.1524)
				(type default)
			)
			(layer "F.SilkS")
		)
		(fp_line
			(start -0.7874 -0.4064)
			(end 0.7874 -0.4064)
			(stroke
				(width 0.1524)
				(type default)
			)
			(layer "F.SilkS")
		)
		(fp_line
			(start 0.7874 0.4064)
			(end -0.7874 0.4064)
			(stroke
				(width 0.1524)
				(type default)
			)
			(layer "F.SilkS")
		)
		(fp_line
			(start -0.7874 0.4064)
			(end -0.7874 -0.4064)
			(stroke
				(width 0.1524)
				(type default)
			)
			(layer "F.SilkS")
		)
		(fp_poly
			(pts
				(xy -0.508 0.2794) (xy -0.508 0.2286) (xy -0.635 0.2286) (xy -0.635 -0.254) (xy -0.5334 -0.254)
				(xy -0.5334 -0.2794) (xy 0.5334 -0.2794) (xy 0.5334 -0.254) (xy 0.635 -0.254) (xy 0.635 0.254) (xy 0.5334 0.254)
				(xy 0.5334 0.2794)
			)
			(stroke
				(width 0)
				(type default)
			)
			(fill no)
			(layer "F.CrtYd")
		)
		(pad "1" smd rect
			(at 0.40005 0 90)
			(size 0.4572 0.508)
			(layers "F.Cu" "F.Mask" "F.Paste")
			(net "SIO_COPEN_N")
		)
		(pad "2" smd rect
			(at -0.40005 0 90)
			(size 0.4572 0.508)
			(layers "F.Cu" "F.Mask" "F.Paste")
			(net "GND")
		)
	)
	(footprint ""
		(layer "F.Cu")
		(at 50.53076 -185.205624 90)
		(property "Reference" "R836"
			(at 4.006088 0.055372 90)
			(unlocked yes)
			(layer "F.SilkS")
			(effects
				(font
					(size 0.7874 0.5842)
					(thickness 0.1524)
				)
				(justify left)
			)
		)
		(property "Value" ""
			(at 0 0 90)
			(layer "F.Fab")
			(effects
				(font
					(size 1.27 1.27)
				)
			)
		)
		(duplicate_pad_numbers_are_jumpers no)
		(fp_line
			(start 0.7874 -0.4064)
			(end 0.7874 0.4064)
			(stroke
				(width 0.1524)
				(type default)
			)
			(layer "F.SilkS")
		)
		(fp_line
			(start -0.7874 -0.4064)
			(end 0.7874 -0.4064)
			(stroke
				(width 0.1524)
				(type default)
			)
			(layer "F.SilkS")
		)
		(fp_line
			(start 0.7874 0.4064)
			(end -0.7874 0.4064)
			(stroke
				(width 0.1524)
				(type default)
			)
			(layer "F.SilkS")
		)
		(fp_line
			(start -0.7874 0.4064)
			(end -0.7874 -0.4064)
			(stroke
				(width 0.1524)
				(type default)
			)
			(layer "F.SilkS")
		)
		(fp_poly
			(pts
				(xy -0.508 0.2794) (xy -0.508 0.2286) (xy -0.635 0.2286) (xy -0.635 -0.254) (xy -0.5334 -0.254)
				(xy -0.5334 -0.2794) (xy 0.5334 -0.2794) (xy 0.5334 -0.254) (xy 0.635 -0.254) (xy 0.635 0.254) (xy 0.5334 0.254)
				(xy 0.5334 0.2794)
			)
			(stroke
				(width 0)
				(type default)
			)
			(fill no)
			(layer "F.CrtYd")
		)
		(pad "1" smd rect
			(at 0.40005 0 90)
			(size 0.4572 0.508)
			(layers "F.Cu" "F.Mask" "F.Paste")
			(net "PSU3_AC_OK_R")
		)
		(pad "2" smd rect
			(at -0.40005 0 90)
			(size 0.4572 0.508)
			(layers "F.Cu" "F.Mask" "F.Paste")
			(net "PSU3_AC_OK")
		)
	)
	(footprint ""
		(layer "F.Cu")
		(at 89.962228 -133.213094 -90)
		(property "Reference" "D37"
			(at -3.582162 1.343406 90)
			(unlocked yes)
			(layer "F.SilkS")
			(effects
				(font
					(size 0.7874 0.5842)
					(thickness 0.1524)
				)
				(justify left)
			)
		)
		(property "Value" ""
			(at 0 0 270)
			(layer "F.Fab")
			(effects
				(font
					(size 1.27 1.27)
				)
			)
		)
		(duplicate_pad_numbers_are_jumpers no)
		(fp_line
			(start -1.3208 0.5588)
			(end -1.3208 -0.5588)
			(stroke
				(width 0.1524)
				(type default)
			)
			(layer "F.SilkS")
		)
		(fp_line
			(start 1.3208 0.5588)
			(end -1.3208 0.5588)
			(stroke
				(width 0.1524)
				(type default)
			)
			(layer "F.SilkS")
		)
		(fp_line
			(start 1.6256 0.5588)
			(end 1.6256 -0.5588)
			(stroke
				(width 0.1524)
				(type default)
			)
			(layer "F.SilkS")
		)
		(fp_line
			(start 1.778 0.5588)
			(end 1.3208 0.5588)
			(stroke
				(width 0.1524)
				(type default)
			)
			(layer "F.SilkS")
		)
		(fp_line
			(start -1.3208 -0.5588)
			(end 1.3208 -0.5588)
			(stroke
				(width 0.1524)
				(type default)
			)
			(layer "F.SilkS")
		)
		(fp_line
			(start 1.3208 -0.5588)
			(end 1.3208 0.5588)
			(stroke
				(width 0.1524)
				(type default)
			)
			(layer "F.SilkS")
		)
		(fp_line
			(start 1.4732 -0.5588)
			(end 1.4732 0.5588)
			(stroke
				(width 0.1524)
				(type default)
			)
			(layer "F.SilkS")
		)
		(fp_line
			(start 1.778 -0.5588)
			(end 1.778 0.5588)
			(stroke
				(width 0.1524)
				(type default)
			)
			(layer "F.SilkS")
		)
		(fp_line
			(start 1.778 -0.5588)
			(end 1.3208 -0.5588)
			(stroke
				(width 0.1524)
				(type default)
			)
			(layer "F.SilkS")
		)
		(fp_circle
			(center 2.4384 0)
			(end 2.4384 -0.413512)
			(stroke
				(width 0.1524)
				(type default)
			)
			(fill no)
			(layer "F.SilkS")
		)
		(fp_rect
			(start -1.1684 0.508)
			(end 1.1684 -0.508)
			(stroke
				(width 0)
				(type default)
			)
			(fill no)
			(layer "F.CrtYd")
		)
		(fp_text user "-"
			(at 1.898396 0.67818 270)
			(unlocked yes)
			(layer "F.SilkS")
			(effects
				(font
					(size 0.7874 0.5842)
					(thickness 0.1524)
				)
				(justify left)
			)
		)
		(pad "A" smd rect
			(at -0.750062 0 270)
			(size 0.8128 0.8128)
			(layers "F.Cu" "F.Mask" "F.Paste")
			(net "P3V3_NODE1")
		)
		(pad "C" smd rect
			(at 0.750062 0 270)
			(size 0.8128 0.8128)
			(layers "F.Cu" "F.Mask" "F.Paste")
			(net "N53313577")
		)
	)
)
